FILE_TYPE = MACRO_DRAWING;
SET COLOR_WIRE YELLOW;
SET COLOR_PROP ORANGE;
SET COLOR_DOT WHITE;
SET COLOR_ARC YELLOW;
SET COLOR_BODY GREEN;
SET COLOR_NOTE PURPLE;
SET PROP_DISPLAY VALUE;
SET PAGE_NUMBER P191;
FORCEADD OFFPAGE..1
(-7900 4400);
FORCEPROP 2 LAST $XR4 215 
J 0
(-8632 4400);
DISPLAY 0.638298 (-8632 4400);
PAINT MONO (-8632 4400);
FORCEPROP 2 LAST $XR3 213 
J 0
(-8512 4400);
DISPLAY 0.638298 (-8512 4400);
PAINT MONO (-8512 4400);
FORCEPROP 2 LAST $XR2 212 
J 0
(-8392 4400);
DISPLAY 0.638298 (-8392 4400);
PAINT MONO (-8392 4400);
FORCEPROP 2 LAST $XR1 211 
J 0
(-8272 4400);
DISPLAY 0.638298 (-8272 4400);
PAINT MONO (-8272 4400);
FORCEPROP 2 LAST $XR0 210 
J 0
(-8152 4400);
DISPLAY 0.638298 (-8152 4400);
PAINT MONO (-8152 4400);
FORCEPROP 2 LAST CDS_LIB standard
J 0
(-7900 4400);
DISPLAY INVISIBLE (-7900 4400);
FORCEPROP 1 LAST OFFPAGE TRUE
J 0
(-7575 4275);
DISPLAY 0.872340 (-7575 4275);
PAINT GREEN (-7575 4275);
DISPLAY INVISIBLE (-7575 4275);
FORCEPROP 1 LAST COMMENT_BODY TRUE
J 0
(-7775 4300);
DISPLAY 0.872340 (-7775 4300);
PAINT GREEN (-7775 4300);
DISPLAY INVISIBLE (-7775 4300);
FORCEPROP 2 LAST PATH I1
J 0
(-8150 4450);
DISPLAY 0.680851 (-8150 4450);
DISPLAY INVISIBLE (-8150 4450);
FORCEADD Q_RES..2
(-4450 3775);
FORCEPROP 1 LAST LOCATION PR511
J 0
(-4405 3900);
DISPLAY 0.489362 (-4405 3900);
PAINT SKYBLUE (-4405 3900);
FORCEPROP 0 LAST $SEC 1
J 0
(-4400 3950);
DISPLAY 0.680851 (-4400 3950);
PAINT MONO (-4400 3950);
DISPLAY INVISIBLE (-4400 3950);
FORCEPROP 0 LAST CDS_SEC 1
J 0
(-4400 3950);
DISPLAY 1.021277 (-4400 3950);
DISPLAY INVISIBLE (-4400 3950);
FORCEPROP 1 LASTPIN (-4450 3875) $PN 1
J 0
(-4445 3837);
DISPLAY 0.489362 (-4445 3837);
PAINT MONO (-4445 3837);
FORCEPROP 1 LASTPIN (-4450 3675) $PN 2
J 0
(-4445 3685);
DISPLAY 0.489362 (-4445 3685);
PAINT MONO (-4445 3685);
FORCEPROP 1 LAST MATERIAL EMPTY
J 0
(-4410 3700);
DISPLAY 0.489362 (-4410 3700);
PAINT RED (-4410 3700);
FORCEPROP 1 LAST WATTAGE 1/8W
J 0
(-4410 3750);
DISPLAY 0.489362 (-4410 3750);
PAINT SKYBLUE (-4410 3750);
FORCEPROP 1 LAST TOLERANCE 1%
J 0
(-4405 3800);
DISPLAY 0.489362 (-4405 3800);
PAINT SKYBLUE (-4405 3800);
FORCEPROP 1 LAST PACK_TYPE 0402LF
J 0
(-4410 3600);
DISPLAY 0.489362 (-4410 3600);
PAINT SKYBLUE (-4410 3600);
FORCEPROP 1 LAST VALUE 1.5
J 0
(-4405 3850);
DISPLAY 0.489362 (-4405 3850);
PAINT SKYBLUE (-4405 3850);
FORCEPROP 2 LAST CDS_LIB pure_quanta
J 0
(-4450 3775);
DISPLAY INVISIBLE (-4450 3775);
FORCEPROP 1 LAST PATH I10
J 0
(-4400 3950);
DISPLAY 0.978723 (-4400 3950);
PAINT WHITE (-4400 3950);
DISPLAY INVISIBLE (-4400 3950);
FORCEPROP 1 LAST PART_NUMBER CS-1504FB00
J 0
(-4410 3650);
DISPLAY 0.489362 (-4410 3650);
PAINT SKYBLUE (-4410 3650);
DISPLAY INVISIBLE (-4410 3650);
FORCEADD Q_CAP..1
(-4450 4300);
FORCEPROP 1 LAST LOCATION PC195
J 0
(-4400 4400);
DISPLAY 0.489362 (-4400 4400);
PAINT SKYBLUE (-4400 4400);
FORCEPROP 0 LAST $SEC 1
J 0
(-4400 4450);
DISPLAY 0.680851 (-4400 4450);
PAINT MONO (-4400 4450);
DISPLAY INVISIBLE (-4400 4450);
FORCEPROP 0 LAST CDS_SEC 1
J 0
(-4400 4450);
DISPLAY 1.021277 (-4400 4450);
DISPLAY INVISIBLE (-4400 4450);
FORCEPROP 1 LASTPIN (-4450 4400) $PN 1
J 0
(-4440 4380);
DISPLAY 0.489362 (-4440 4380);
PAINT MONO (-4440 4380);
FORCEPROP 1 LASTPIN (-4450 4200) $PN 2
J 0
(-4440 4180);
DISPLAY 0.489362 (-4440 4180);
PAINT MONO (-4440 4180);
FORCEPROP 1 LAST TOLERANCE 10%
J 0
(-4400 4250);
DISPLAY 0.489362 (-4400 4250);
PAINT SKYBLUE (-4400 4250);
FORCEPROP 1 LAST MATERIAL EMPTY
J 0
(-4400 4200);
DISPLAY 0.489362 (-4400 4200);
PAINT RED (-4400 4200);
FORCEPROP 1 LAST VALUE 560PF
J 0
(-4400 4350);
DISPLAY 0.489362 (-4400 4350);
PAINT SKYBLUE (-4400 4350);
FORCEPROP 1 LAST VOLTAGE 50V
J 0
(-4400 4300);
DISPLAY 0.489362 (-4400 4300);
PAINT SKYBLUE (-4400 4300);
FORCEPROP 1 LAST PACK_TYPE C0402
J 0
(-4400 4100);
DISPLAY 0.489362 (-4400 4100);
PAINT SKYBLUE (-4400 4100);
FORCEPROP 2 LAST CDS_LIB pure_quanta
J 0
(-4450 4300);
DISPLAY INVISIBLE (-4450 4300);
FORCEPROP 1 LAST PATH I11
J 0
(-4400 4450);
DISPLAY 0.978723 (-4400 4450);
PAINT WHITE (-4400 4450);
DISPLAY INVISIBLE (-4400 4450);
FORCEPROP 1 LAST PART_NUMBER CH1566K1B09
J 0
(-4400 4150);
DISPLAY 0.489362 (-4400 4150);
PAINT SKYBLUE (-4400 4150);
DISPLAY INVISIBLE (-4400 4150);
FORCEADD UNIVERSAL_GND..1
(-7350 4650);
FORCEPROP 3 LASTPIN (-7350 4700) SIG_NAME GND\g
J 0
(-7340 4710);
DISPLAY 0.659574 (-7340 4710);
PAINT MONO (-7340 4710);
DISPLAY INVISIBLE (-7340 4710);
FORCEPROP 2 LAST CDS_LIB pure_quanta_power
J 0
(-7350 4650);
DISPLAY INVISIBLE (-7350 4650);
FORCEPROP 1 LAST HDL_POWER GND
J 1
(-7325 4575);
DISPLAY 0.872340 (-7325 4575);
PAINT GREEN (-7325 4575);
DISPLAY INVISIBLE (-7325 4575);
FORCEPROP 1 LAST PATH I12
J 0
(-7275 4650);
DISPLAY 0.872340 (-7275 4650);
PAINT AQUA (-7275 4650);
DISPLAY INVISIBLE (-7275 4650);
FORCEADD Q_CAP..1
(-7350 4850);
FORCEPROP 1 LAST LOCATION PC346
J 0
(-7300 4950);
DISPLAY 0.489362 (-7300 4950);
PAINT SKYBLUE (-7300 4950);
FORCEPROP 0 LAST $SEC 1
J 0
(-7300 5000);
DISPLAY 0.680851 (-7300 5000);
PAINT MONO (-7300 5000);
DISPLAY INVISIBLE (-7300 5000);
FORCEPROP 0 LAST CDS_SEC 1
J 0
(-7300 5000);
DISPLAY 1.021277 (-7300 5000);
DISPLAY INVISIBLE (-7300 5000);
FORCEPROP 1 LASTPIN (-7350 4950) $PN 1
J 0
(-7340 4930);
DISPLAY 0.489362 (-7340 4930);
PAINT MONO (-7340 4930);
FORCEPROP 1 LASTPIN (-7350 4750) $PN 2
J 0
(-7340 4730);
DISPLAY 0.489362 (-7340 4730);
PAINT MONO (-7340 4730);
FORCEPROP 1 LAST MATERIAL X6S
J 0
(-7300 4750);
DISPLAY 0.489362 (-7300 4750);
PAINT SKYBLUE (-7300 4750);
FORCEPROP 1 LAST VALUE 2.2UF
J 0
(-7300 4900);
DISPLAY 0.489362 (-7300 4900);
PAINT SKYBLUE (-7300 4900);
FORCEPROP 1 LAST VOLTAGE 10V
J 0
(-7300 4850);
DISPLAY 0.489362 (-7300 4850);
PAINT SKYBLUE (-7300 4850);
FORCEPROP 1 LAST PACK_TYPE C0402
J 0
(-7300 4650);
DISPLAY 0.489362 (-7300 4650);
PAINT SKYBLUE (-7300 4650);
FORCEPROP 1 LAST TOLERANCE 10%
J 0
(-7300 4800);
DISPLAY 0.489362 (-7300 4800);
PAINT SKYBLUE (-7300 4800);
FORCEPROP 2 LAST CDS_LIB pure_quanta
J 0
(-7350 4850);
DISPLAY INVISIBLE (-7350 4850);
FORCEPROP 1 LAST PATH I13
J 0
(-7300 5000);
DISPLAY 0.978723 (-7300 5000);
PAINT WHITE (-7300 5000);
DISPLAY INVISIBLE (-7300 5000);
FORCEPROP 1 LAST PART_NUMBER CH5222KEB01
J 0
(-7300 4700);
DISPLAY 0.489362 (-7300 4700);
PAINT SKYBLUE (-7300 4700);
DISPLAY INVISIBLE (-7300 4700);
FORCEADD Q_RES..2
(-7350 5400);
FORCEPROP 1 LAST LOCATION PR213
J 0
(-7305 5525);
DISPLAY 0.489362 (-7305 5525);
PAINT SKYBLUE (-7305 5525);
FORCEPROP 0 LAST $SEC 1
J 0
(-7300 5575);
DISPLAY 0.680851 (-7300 5575);
PAINT MONO (-7300 5575);
DISPLAY INVISIBLE (-7300 5575);
FORCEPROP 0 LAST CDS_SEC 1
J 0
(-7300 5575);
DISPLAY 1.021277 (-7300 5575);
DISPLAY INVISIBLE (-7300 5575);
FORCEPROP 1 LASTPIN (-7350 5500) $PN 1
J 0
(-7345 5462);
DISPLAY 0.489362 (-7345 5462);
PAINT MONO (-7345 5462);
FORCEPROP 1 LASTPIN (-7350 5300) $PN 2
J 0
(-7345 5310);
DISPLAY 0.489362 (-7345 5310);
PAINT MONO (-7345 5310);
FORCEPROP 1 LAST WATTAGE 1/16W
J 0
(-7300 5375);
DISPLAY 0.489362 (-7300 5375);
PAINT SKYBLUE (-7300 5375);
FORCEPROP 1 LAST TOLERANCE 1%
J 0
(-7300 5425);
DISPLAY 0.489362 (-7300 5425);
PAINT SKYBLUE (-7300 5425);
FORCEPROP 1 LAST VALUE 2.2
J 0
(-7300 5475);
DISPLAY 0.489362 (-7300 5475);
PAINT SKYBLUE (-7300 5475);
FORCEPROP 1 LAST PACK_TYPE 0402LF
J 0
(-7300 5225);
DISPLAY 0.489362 (-7300 5225);
PAINT SKYBLUE (-7300 5225);
FORCEPROP 1 LAST MATERIAL CHIP
J 0
(-7300 5325);
DISPLAY 0.489362 (-7300 5325);
PAINT SKYBLUE (-7300 5325);
FORCEPROP 2 LAST CDS_LIB pure_quanta
J 0
(-7350 5400);
DISPLAY INVISIBLE (-7350 5400);
FORCEPROP 1 LAST PATH I14
J 0
(-7300 5575);
DISPLAY 0.978723 (-7300 5575);
PAINT WHITE (-7300 5575);
DISPLAY INVISIBLE (-7300 5575);
FORCEPROP 1 LAST PART_NUMBER CS-2202FB01
J 0
(-7300 5275);
DISPLAY 0.489362 (-7300 5275);
PAINT SKYBLUE (-7300 5275);
DISPLAY INVISIBLE (-7300 5275);
FORCEADD VCC_CORE..1
(-7350 5800);
FORCEPROP 3 LASTPIN (-7350 5750) SIG_NAME PVDDCR_CPU0_P1_PVCC\g
J 0
(-7340 5760);
DISPLAY 0.659574 (-7340 5760);
PAINT MONO (-7340 5760);
DISPLAY INVISIBLE (-7340 5760);
FORCEPROP 1 LAST HDL_POWER PVDDCR_CPU0_P1_PVCC
J 1
(-7350 5850);
DISPLAY 0.489362 (-7350 5850);
PAINT GREEN (-7350 5850);
FORCEPROP 2 LAST CDS_LIB pure_quanta_power
J 0
(-7350 5800);
DISPLAY INVISIBLE (-7350 5800);
FORCEPROP 1 LAST PATH I15
J 0
(-7300 5825);
DISPLAY 0.872340 (-7300 5825);
PAINT AQUA (-7300 5825);
DISPLAY INVISIBLE (-7300 5825);
FORCEADD OFFPAGE..2
R 2
(-7000 4500);
FORCEPROP 2 LAST $XR0 210 
J 0
(-7255 4500);
DISPLAY 0.638298 (-7255 4500);
PAINT MONO (-7255 4500);
FORCEPROP 2 LAST CDS_LIB standard
J 2
(-7000 4500);
DISPLAY INVISIBLE (-7000 4500);
FORCEPROP 1 LAST OFFPAGE TRUE
J 2
(-7325 4375);
DISPLAY 0.872340 (-7325 4375);
PAINT GREEN (-7325 4375);
DISPLAY INVISIBLE (-7325 4375);
FORCEPROP 1 LAST COMMENT_BODY TRUE
J 2
(-6955 4405);
DISPLAY 0.872340 (-6955 4405);
PAINT GREEN (-6955 4405);
DISPLAY INVISIBLE (-6955 4405);
FORCEPROP 2 LAST PATH I16
J 0
(-7250 4550);
DISPLAY 0.680851 (-7250 4550);
DISPLAY INVISIBLE (-7250 4550);
FORCEADD UNIVERSAL_GND..1
(-7000 5150);
FORCEPROP 3 LASTPIN (-7000 5200) SIG_NAME GND\g
J 0
(-6990 5210);
DISPLAY 0.659574 (-6990 5210);
PAINT MONO (-6990 5210);
DISPLAY INVISIBLE (-6990 5210);
FORCEPROP 2 LAST CDS_LIB pure_quanta_power
J 0
(-7000 5150);
DISPLAY INVISIBLE (-7000 5150);
FORCEPROP 1 LAST HDL_POWER GND
J 1
(-6975 5075);
DISPLAY 0.872340 (-6975 5075);
PAINT GREEN (-6975 5075);
DISPLAY INVISIBLE (-6975 5075);
FORCEPROP 1 LAST PATH I17
J 0
(-6925 5150);
DISPLAY 0.872340 (-6925 5150);
PAINT AQUA (-6925 5150);
DISPLAY INVISIBLE (-6925 5150);
FORCEADD Q_CAP..1
(-7000 5425);
FORCEPROP 1 LAST LOCATION PC347_SOP1_3
J 0
(-6950 5525);
DISPLAY 0.489362 (-6950 5525);
PAINT SKYBLUE (-6950 5525);
FORCEPROP 0 LAST $SEC 1
J 0
(-6950 5575);
DISPLAY 0.680851 (-6950 5575);
PAINT MONO (-6950 5575);
DISPLAY INVISIBLE (-6950 5575);
FORCEPROP 0 LAST CDS_SEC 1
J 0
(-6950 5575);
DISPLAY 1.021277 (-6950 5575);
DISPLAY INVISIBLE (-6950 5575);
FORCEPROP 1 LASTPIN (-7000 5525) $PN 1
J 0
(-6990 5505);
DISPLAY 0.489362 (-6990 5505);
PAINT MONO (-6990 5505);
FORCEPROP 1 LASTPIN (-7000 5325) $PN 2
J 0
(-6990 5305);
DISPLAY 0.489362 (-6990 5305);
PAINT MONO (-6990 5305);
FORCEPROP 1 LAST MATERIAL X6S
J 0
(-6950 5325);
DISPLAY 0.489362 (-6950 5325);
PAINT SKYBLUE (-6950 5325);
FORCEPROP 1 LAST TOLERANCE 10%
J 0
(-6950 5375);
DISPLAY 0.489362 (-6950 5375);
PAINT SKYBLUE (-6950 5375);
FORCEPROP 1 LAST VALUE 2.2UF
J 0
(-6950 5475);
DISPLAY 0.489362 (-6950 5475);
PAINT SKYBLUE (-6950 5475);
FORCEPROP 1 LAST VOLTAGE 10V
J 0
(-6950 5425);
DISPLAY 0.489362 (-6950 5425);
PAINT SKYBLUE (-6950 5425);
FORCEPROP 1 LAST PACK_TYPE C0402
J 0
(-6950 5225);
DISPLAY 0.489362 (-6950 5225);
PAINT SKYBLUE (-6950 5225);
FORCEPROP 2 LAST CDS_LIB pure_quanta
J 0
(-7000 5425);
DISPLAY INVISIBLE (-7000 5425);
FORCEPROP 1 LAST PATH I18
J 0
(-6950 5575);
DISPLAY 0.978723 (-6950 5575);
PAINT WHITE (-6950 5575);
DISPLAY INVISIBLE (-6950 5575);
FORCEPROP 1 LAST PART_NUMBER CH5222KEB01
J 0
(-6950 5275);
DISPLAY 0.489362 (-6950 5275);
PAINT SKYBLUE (-6950 5275);
DISPLAY INVISIBLE (-6950 5275);
FORCEADD Q_CAP..1
(-5050 5375);
FORCEPROP 1 LAST LOCATION PC348_3
J 0
(-5000 5475);
DISPLAY 0.489362 (-5000 5475);
PAINT SKYBLUE (-5000 5475);
FORCEPROP 0 LAST $SEC 1
J 0
(-5000 5525);
DISPLAY 0.680851 (-5000 5525);
PAINT MONO (-5000 5525);
DISPLAY INVISIBLE (-5000 5525);
FORCEPROP 0 LAST CDS_SEC 1
J 0
(-5000 5525);
DISPLAY 1.021277 (-5000 5525);
DISPLAY INVISIBLE (-5000 5525);
FORCEPROP 1 LASTPIN (-5050 5475) $PN 1
J 0
(-5040 5455);
DISPLAY 0.489362 (-5040 5455);
PAINT MONO (-5040 5455);
FORCEPROP 1 LASTPIN (-5050 5275) $PN 2
J 0
(-5040 5255);
DISPLAY 0.489362 (-5040 5255);
PAINT MONO (-5040 5255);
FORCEPROP 1 LAST MATERIAL X7R
J 0
(-5000 5275);
DISPLAY 0.489362 (-5000 5275);
PAINT SKYBLUE (-5000 5275);
FORCEPROP 1 LAST VALUE 0.1UF
J 0
(-5000 5425);
DISPLAY 0.489362 (-5000 5425);
PAINT SKYBLUE (-5000 5425);
FORCEPROP 1 LAST TOLERANCE 10%
J 0
(-5000 5325);
DISPLAY 0.489362 (-5000 5325);
PAINT SKYBLUE (-5000 5325);
FORCEPROP 1 LAST VOLTAGE 25V
J 0
(-5000 5375);
DISPLAY 0.489362 (-5000 5375);
PAINT SKYBLUE (-5000 5375);
FORCEPROP 1 LAST PACK_TYPE 0402
J 0
(-5000 5175);
DISPLAY 0.489362 (-5000 5175);
PAINT SKYBLUE (-5000 5175);
FORCEPROP 2 LAST CDS_LIB pure_quanta
J 0
(-5050 5375);
DISPLAY INVISIBLE (-5050 5375);
FORCEPROP 1 LAST PATH I19
J 0
(-5000 5525);
DISPLAY 0.978723 (-5000 5525);
PAINT WHITE (-5000 5525);
DISPLAY INVISIBLE (-5000 5525);
FORCEPROP 1 LAST PART_NUMBER CH4104K1B00
J 0
(-5000 5225);
DISPLAY 0.489362 (-5000 5225);
PAINT SKYBLUE (-5000 5225);
DISPLAY INVISIBLE (-5000 5225);
FORCEADD Q_CAP..1
(-7675 4225);
FORCEPROP 1 LAST LOCATION PC345_9
J 0
(-7625 4325);
DISPLAY 0.489362 (-7625 4325);
PAINT SKYBLUE (-7625 4325);
FORCEPROP 0 LAST $SEC 1
J 0
(-7625 4350);
DISPLAY 0.680851 (-7625 4350);
PAINT MONO (-7625 4350);
DISPLAY INVISIBLE (-7625 4350);
FORCEPROP 0 LAST CDS_SEC 1
J 0
(-7625 4350);
DISPLAY 1.021277 (-7625 4350);
DISPLAY INVISIBLE (-7625 4350);
FORCEPROP 1 LASTPIN (-7675 4325) $PN 1
J 0
(-7665 4305);
DISPLAY 0.489362 (-7665 4305);
PAINT MONO (-7665 4305);
FORCEPROP 1 LASTPIN (-7675 4125) $PN 2
J 0
(-7665 4105);
DISPLAY 0.489362 (-7665 4105);
PAINT MONO (-7665 4105);
FORCEPROP 1 LAST MATERIAL X7R
J 0
(-7625 4125);
DISPLAY 0.489362 (-7625 4125);
PAINT SKYBLUE (-7625 4125);
FORCEPROP 1 LAST TOLERANCE 10%
J 0
(-7625 4175);
DISPLAY 0.489362 (-7625 4175);
PAINT SKYBLUE (-7625 4175);
FORCEPROP 1 LAST VALUE 0.1UF
J 0
(-7625 4275);
DISPLAY 0.489362 (-7625 4275);
PAINT SKYBLUE (-7625 4275);
FORCEPROP 1 LAST VOLTAGE 25V
J 0
(-7625 4225);
DISPLAY 0.489362 (-7625 4225);
PAINT SKYBLUE (-7625 4225);
FORCEPROP 1 LAST PACK_TYPE 0402
J 0
(-7625 4025);
DISPLAY 0.489362 (-7625 4025);
PAINT SKYBLUE (-7625 4025);
FORCEPROP 2 LAST CDS_LIB pure_quanta
J 0
(-7675 4225);
DISPLAY INVISIBLE (-7675 4225);
FORCEPROP 1 LAST PATH I2
J 0
(-7625 4375);
DISPLAY 0.978723 (-7625 4375);
PAINT WHITE (-7625 4375);
DISPLAY INVISIBLE (-7625 4375);
FORCEPROP 1 LAST PART_NUMBER CH4104K1B00
J 0
(-7625 4075);
DISPLAY 0.489362 (-7625 4075);
PAINT SKYBLUE (-7625 4075);
DISPLAY INVISIBLE (-7625 4075);
FORCEADD Q_CAP..1
(-4650 5375);
FORCEPROP 1 LAST LOCATION PC349_3
J 0
(-4600 5475);
DISPLAY 0.489362 (-4600 5475);
PAINT SKYBLUE (-4600 5475);
FORCEPROP 0 LAST $SEC 1
J 0
(-4600 5500);
DISPLAY 0.680851 (-4600 5500);
PAINT MONO (-4600 5500);
DISPLAY INVISIBLE (-4600 5500);
FORCEPROP 0 LAST CDS_SEC 1
J 0
(-4600 5500);
DISPLAY 1.021277 (-4600 5500);
DISPLAY INVISIBLE (-4600 5500);
FORCEPROP 1 LASTPIN (-4650 5475) $PN 1
J 0
(-4640 5455);
DISPLAY 0.489362 (-4640 5455);
PAINT MONO (-4640 5455);
FORCEPROP 1 LASTPIN (-4650 5275) $PN 2
J 0
(-4640 5255);
DISPLAY 0.489362 (-4640 5255);
PAINT MONO (-4640 5255);
FORCEPROP 1 LAST MATERIAL X6S
J 0
(-4600 5275);
DISPLAY 0.489362 (-4600 5275);
PAINT SKYBLUE (-4600 5275);
FORCEPROP 1 LAST VALUE 1UF
J 0
(-4600 5425);
DISPLAY 0.489362 (-4600 5425);
PAINT SKYBLUE (-4600 5425);
FORCEPROP 1 LAST PACK_TYPE C0402
J 0
(-4600 5175);
DISPLAY 0.489362 (-4600 5175);
PAINT SKYBLUE (-4600 5175);
FORCEPROP 1 LAST TOLERANCE 10%
J 0
(-4600 5325);
DISPLAY 0.489362 (-4600 5325);
PAINT SKYBLUE (-4600 5325);
FORCEPROP 1 LAST VOLTAGE 25V
J 0
(-4600 5375);
DISPLAY 0.489362 (-4600 5375);
PAINT SKYBLUE (-4600 5375);
FORCEPROP 2 LAST CDS_LIB pure_quanta
J 0
(-4650 5375);
DISPLAY INVISIBLE (-4650 5375);
FORCEPROP 1 LAST PATH I20
J 0
(-4600 5525);
DISPLAY 0.978723 (-4600 5525);
PAINT WHITE (-4600 5525);
DISPLAY INVISIBLE (-4600 5525);
FORCEPROP 1 LAST PART_NUMBER CH5104KEB02
J 0
(-4600 5225);
DISPLAY 0.489362 (-4600 5225);
PAINT SKYBLUE (-4600 5225);
DISPLAY INVISIBLE (-4600 5225);
FORCEADD Q_RES..1
(-4475 4850);
FORCEPROP 1 LAST LOCATION PR215
J 0
(-4500 4900);
DISPLAY 0.489362 (-4500 4900);
PAINT SKYBLUE (-4500 4900);
FORCEPROP 0 LAST $SEC 1
J 0
(-4450 4925);
DISPLAY 0.680851 (-4450 4925);
PAINT MONO (-4450 4925);
DISPLAY INVISIBLE (-4450 4925);
FORCEPROP 0 LAST CDS_SEC 1
J 0
(-4450 4925);
DISPLAY 1.021277 (-4450 4925);
DISPLAY INVISIBLE (-4450 4925);
FORCEPROP 1 LASTPIN (-4575 4850) $PN 1
J 0
(-4563 4862);
DISPLAY 0.489362 (-4563 4862);
PAINT MONO (-4563 4862);
FORCEPROP 1 LASTPIN (-4375 4850) $PN 2
J 0
(-4413 4862);
DISPLAY 0.489362 (-4413 4862);
PAINT MONO (-4413 4862);
FORCEPROP 1 LAST PACK_TYPE 0402LF
J 0
(-4375 4750);
DISPLAY 0.489362 (-4375 4750);
PAINT SKYBLUE (-4375 4750);
FORCEPROP 1 LAST TOLERANCE 1%
J 0
(-4350 4875);
DISPLAY 0.489362 (-4350 4875);
PAINT SKYBLUE (-4350 4875);
FORCEPROP 1 LAST WATTAGE 1/16W
J 0
(-4375 4800);
DISPLAY 0.489362 (-4375 4800);
PAINT SKYBLUE (-4375 4800);
FORCEPROP 1 LAST MATERIAL CHIP
J 0
(-4725 4750);
DISPLAY 0.489362 (-4725 4750);
PAINT SKYBLUE (-4725 4750);
FORCEPROP 1 LAST VALUE 5.6
J 2
(-4600 4875);
DISPLAY 0.489362 (-4600 4875);
PAINT SKYBLUE (-4600 4875);
FORCEPROP 2 LAST CDS_LIB pure_quanta
J 0
(-4475 4850);
DISPLAY INVISIBLE (-4475 4850);
FORCEPROP 1 LAST PATH I21
J 0
(-4525 5000);
DISPLAY 0.978723 (-4525 5000);
PAINT WHITE (-4525 5000);
DISPLAY INVISIBLE (-4525 5000);
FORCEPROP 1 LAST PART_NUMBER CS-5602FB01
J 0
(-4725 4800);
DISPLAY 0.489362 (-4725 4800);
PAINT SKYBLUE (-4725 4800);
DISPLAY INVISIBLE (-4725 4800);
FORCEADD Q_CAP..1
(-4325 5375);
FORCEPROP 1 LAST LOCATION PC350_3
J 0
(-4275 5475);
DISPLAY 0.489362 (-4275 5475);
PAINT SKYBLUE (-4275 5475);
FORCEPROP 0 LAST $SEC 1
J 0
(-4275 5500);
DISPLAY 0.680851 (-4275 5500);
PAINT MONO (-4275 5500);
DISPLAY INVISIBLE (-4275 5500);
FORCEPROP 0 LAST CDS_SEC 1
J 0
(-4275 5500);
DISPLAY 1.021277 (-4275 5500);
DISPLAY INVISIBLE (-4275 5500);
FORCEPROP 1 LASTPIN (-4325 5475) $PN 1
J 0
(-4315 5455);
DISPLAY 0.489362 (-4315 5455);
PAINT MONO (-4315 5455);
FORCEPROP 1 LASTPIN (-4325 5275) $PN 2
J 0
(-4315 5255);
DISPLAY 0.489362 (-4315 5255);
PAINT MONO (-4315 5255);
FORCEPROP 1 LAST PACK_TYPE C0805
J 0
(-4275 5175);
DISPLAY 0.489362 (-4275 5175);
PAINT SKYBLUE (-4275 5175);
FORCEPROP 1 LAST MATERIAL X6S
J 0
(-4275 5275);
DISPLAY 0.489362 (-4275 5275);
PAINT SKYBLUE (-4275 5275);
FORCEPROP 1 LAST VALUE 22UF
J 0
(-4275 5425);
DISPLAY 0.489362 (-4275 5425);
PAINT SKYBLUE (-4275 5425);
FORCEPROP 1 LAST VOLTAGE 16V
J 0
(-4275 5375);
DISPLAY 0.489362 (-4275 5375);
PAINT SKYBLUE (-4275 5375);
FORCEPROP 1 LAST TOLERANCE 20%
J 0
(-4275 5325);
DISPLAY 0.489362 (-4275 5325);
PAINT SKYBLUE (-4275 5325);
FORCEPROP 2 LAST CDS_LIB pure_quanta
J 0
(-4325 5375);
DISPLAY INVISIBLE (-4325 5375);
FORCEPROP 1 LAST PATH I22
J 0
(-4275 5525);
DISPLAY 0.978723 (-4275 5525);
PAINT WHITE (-4275 5525);
DISPLAY INVISIBLE (-4275 5525);
FORCEPROP 1 LAST PART_NUMBER CH6223MEA01
J 0
(-4275 5225);
DISPLAY 0.489362 (-4275 5225);
PAINT SKYBLUE (-4275 5225);
DISPLAY INVISIBLE (-4275 5225);
FORCEADD Q_RES..1
(-4000 3300);
FORCEPROP 1 LAST LOCATION PR216
J 0
(-4025 3350);
DISPLAY 0.489362 (-4025 3350);
PAINT SKYBLUE (-4025 3350);
FORCEPROP 0 LAST $SEC 1
J 0
(-4000 3375);
DISPLAY 0.680851 (-4000 3375);
PAINT MONO (-4000 3375);
DISPLAY INVISIBLE (-4000 3375);
FORCEPROP 0 LAST CDS_SEC 1
J 0
(-4000 3375);
DISPLAY 1.021277 (-4000 3375);
DISPLAY INVISIBLE (-4000 3375);
FORCEPROP 1 LASTPIN (-4100 3300) $PN 1
J 0
(-4088 3312);
DISPLAY 0.489362 (-4088 3312);
PAINT MONO (-4088 3312);
FORCEPROP 1 LASTPIN (-3900 3300) $PN 2
J 0
(-3938 3312);
DISPLAY 0.489362 (-3938 3312);
PAINT MONO (-3938 3312);
FORCEPROP 1 LAST MATERIAL CHIP
J 0
(-4250 3200);
DISPLAY 0.489362 (-4250 3200);
PAINT SKYBLUE (-4250 3200);
FORCEPROP 1 LAST PACK_TYPE 0402LF
J 0
(-3900 3200);
DISPLAY 0.489362 (-3900 3200);
PAINT SKYBLUE (-3900 3200);
FORCEPROP 1 LAST VALUE 0
J 2
(-4125 3325);
DISPLAY 0.489362 (-4125 3325);
PAINT SKYBLUE (-4125 3325);
FORCEPROP 1 LAST TOLERANCE 5%
J 0
(-3875 3325);
DISPLAY 0.489362 (-3875 3325);
PAINT SKYBLUE (-3875 3325);
FORCEPROP 1 LAST WATTAGE 1/16W
J 0
(-3900 3250);
DISPLAY 0.489362 (-3900 3250);
PAINT SKYBLUE (-3900 3250);
FORCEPROP 2 LAST CDS_LIB pure_quanta
J 0
(-4000 3300);
DISPLAY INVISIBLE (-4000 3300);
FORCEPROP 1 LAST PATH I23
J 0
(-4050 3450);
DISPLAY 0.978723 (-4050 3450);
PAINT WHITE (-4050 3450);
DISPLAY INVISIBLE (-4050 3450);
FORCEPROP 1 LAST PART_NUMBER CS00002JB13
J 0
(-4250 3250);
DISPLAY 0.489362 (-4250 3250);
PAINT SKYBLUE (-4250 3250);
DISPLAY INVISIBLE (-4250 3250);
FORCEADD UNIVERSAL_GND..1
(-3825 4150);
FORCEPROP 3 LASTPIN (-3825 4200) SIG_NAME GND\g
J 0
(-3815 4210);
DISPLAY 0.659574 (-3815 4210);
PAINT MONO (-3815 4210);
DISPLAY INVISIBLE (-3815 4210);
FORCEPROP 2 LAST CDS_LIB pure_quanta_power
J 0
(-3825 4150);
DISPLAY INVISIBLE (-3825 4150);
FORCEPROP 1 LAST HDL_POWER GND
J 1
(-3800 4075);
DISPLAY 0.872340 (-3800 4075);
PAINT GREEN (-3800 4075);
DISPLAY INVISIBLE (-3800 4075);
FORCEPROP 1 LAST PATH I24
J 0
(-3750 4150);
DISPLAY 0.872340 (-3750 4150);
PAINT AQUA (-3750 4150);
DISPLAY INVISIBLE (-3750 4150);
FORCEADD Q_INDUCTOR..1
(-3650 4275);
FORCEPROP 1 LAST LOCATION PL34
J 0
(-3800 4425);
DISPLAY 0.574468 (-3800 4425);
PAINT SKYBLUE (-3800 4425);
FORCEPROP 0 LAST $SEC 1
J 0
(-3800 4475);
DISPLAY 0.680851 (-3800 4475);
PAINT MONO (-3800 4475);
DISPLAY INVISIBLE (-3800 4475);
FORCEPROP 0 LAST CDS_SEC 1
J 0
(-3800 4450);
DISPLAY 1.021277 (-3800 4450);
DISPLAY INVISIBLE (-3800 4450);
FORCEPROP 0 LASTPIN (-3750 4250) $PN 1
J 2
(-3760 4260);
DISPLAY 0.680851 (-3760 4260);
PAINT MONO (-3760 4260);
FORCEPROP 0 LASTPIN (-3550 4250) $PN 2
J 0
(-3540 4260);
DISPLAY 0.680851 (-3540 4260);
PAINT MONO (-3540 4260);
FORCEPROP 2 LAST PACK_TYPE SMLF
J 0
(-3800 4375);
DISPLAY 0.617021 (-3800 4375);
FORCEPROP 1 LAST MATERIAL IND
J 0
(-3800 4300);
DISPLAY 0.468085 (-3800 4300);
PAINT SKYBLUE (-3800 4300);
FORCEPROP 2 LAST VALUE 0.22UH/33A
J 0
(-3800 4350);
DISPLAY 0.489362 (-3800 4350);
PAINT SKYBLUE (-3800 4350);
FORCEPROP 1 LAST NEEDS_NO_SIZE TRUE
J 0
(-3650 4275);
DISPLAY 0.468085 (-3650 4275);
PAINT GREEN (-3650 4275);
DISPLAY INVISIBLE (-3650 4275);
FORCEPROP 2 LAST CDS_LIB pure_quanta
J 0
(-3650 4275);
DISPLAY INVISIBLE (-3650 4275);
FORCEPROP 1 LAST PATH I25
J 0
(-3575 4330);
DISPLAY 0.723404 (-3575 4330);
PAINT GREEN (-3575 4330);
DISPLAY INVISIBLE (-3575 4330);
FORCEPROP 1 LAST PART_NUMBER CV+22Y0EZ00
J 0
(-3800 4325);
DISPLAY 0.468085 (-3800 4325);
PAINT SKYBLUE (-3800 4325);
DISPLAY INVISIBLE (-3800 4325);
FORCEADD Q_INDUCTOR4P_14..1
(-2650 4375);
FORCEPROP 1 LAST LOCATION PL38
J 0
(-2875 4630);
DISPLAY 0.489362 (-2875 4630);
PAINT SKYBLUE (-2875 4630);
FORCEPROP 0 LAST $SEC 1
J 0
(-2875 4775);
DISPLAY 0.680851 (-2875 4775);
PAINT MONO (-2875 4775);
DISPLAY INVISIBLE (-2875 4775);
FORCEPROP 0 LAST CDS_SEC 1
J 0
(-2875 4775);
DISPLAY 1.021277 (-2875 4775);
DISPLAY INVISIBLE (-2875 4775);
FORCEPROP 0 LASTPIN (-3050 4500) $PN 1
J 2
(-3060 4510);
DISPLAY 0.489362 (-3060 4510);
PAINT MONO (-3060 4510);
FORCEPROP 0 LASTPIN (-3050 4250) $PN 2
J 2
(-3060 4260);
DISPLAY 0.489362 (-3060 4260);
PAINT MONO (-3060 4260);
FORCEPROP 0 LASTPIN (-2250 4250) $PN 3
J 0
(-2240 4260);
DISPLAY 0.489362 (-2240 4260);
PAINT MONO (-2240 4260);
FORCEPROP 0 LASTPIN (-2250 4500) $PN 4
J 0
(-2240 4510);
DISPLAY 0.489362 (-2240 4510);
PAINT MONO (-2240 4510);
FORCEPROP 2 LAST PART_TYPE SMLF
J 0
(-2875 4725);
DISPLAY 1.021277 (-2875 4725);
FORCEPROP 1 LAST MATERIAL IND
J 0
(-2875 4585);
DISPLAY 0.489362 (-2875 4585);
PAINT SKYBLUE (-2875 4585);
FORCEPROP 2 LAST VALUE 150NH
J 0
(-2875 4675);
DISPLAY 0.489362 (-2875 4675);
PAINT SKYBLUE (-2875 4675);
FORCEPROP 2 LAST CDS_LIB pure_quanta
J 0
(-2650 4375);
DISPLAY INVISIBLE (-2650 4375);
FORCEPROP 1 LAST NEEDS_NO_SIZE TRUE
J 0
(-2650 4375);
DISPLAY 0.468085 (-2650 4375);
PAINT GREEN (-2650 4375);
DISPLAY INVISIBLE (-2650 4375);
FORCEPROP 1 LAST PATH I26
J 0
(-2450 4530);
DISPLAY 0.723404 (-2450 4530);
PAINT GREEN (-2450 4530);
DISPLAY INVISIBLE (-2450 4530);
FORCEPROP 1 LAST PART_NUMBER CV+15^0TZ04
J 0
(-2875 4535);
DISPLAY 0.489362 (-2875 4535);
PAINT SKYBLUE (-2875 4535);
DISPLAY INVISIBLE (-2875 4535);
FORCEADD OFFPAGE..3
(-1850 4250);
FORCEPROP 2 LAST $XR0 215 
J 0
(-1636 4250);
DISPLAY 0.638298 (-1636 4250);
PAINT MONO (-1636 4250);
FORCEPROP 2 LAST CDS_LIB standard
J 2
(-1850 4250);
DISPLAY INVISIBLE (-1850 4250);
FORCEPROP 1 LAST OFFPAGE TRUE
J 0
(-1525 4125);
DISPLAY 0.872340 (-1525 4125);
PAINT GREEN (-1525 4125);
DISPLAY INVISIBLE (-1525 4125);
FORCEPROP 1 LAST COMMENT_BODY TRUE
J 0
(-1900 4150);
DISPLAY 0.872340 (-1900 4150);
PAINT GREEN (-1900 4150);
DISPLAY INVISIBLE (-1900 4150);
FORCEPROP 2 LAST PATH I27
J 0
(-1625 4300);
DISPLAY 0.680851 (-1625 4300);
DISPLAY INVISIBLE (-1625 4300);
FORCEADD Q_CAP..1
(-1425 4325);
FORCEPROP 1 LAST LOCATION PC354_3
J 0
(-1375 4425);
DISPLAY 0.489362 (-1375 4425);
PAINT SKYBLUE (-1375 4425);
FORCEPROP 0 LAST $SEC 1
J 0
(-1375 4450);
DISPLAY 0.680851 (-1375 4450);
PAINT MONO (-1375 4450);
DISPLAY INVISIBLE (-1375 4450);
FORCEPROP 0 LAST CDS_SEC 1
J 0
(-1375 4450);
DISPLAY 1.021277 (-1375 4450);
DISPLAY INVISIBLE (-1375 4450);
FORCEPROP 1 LASTPIN (-1425 4425) $PN 1
J 0
(-1415 4405);
DISPLAY 0.489362 (-1415 4405);
PAINT MONO (-1415 4405);
FORCEPROP 1 LASTPIN (-1425 4225) $PN 2
J 0
(-1415 4205);
DISPLAY 0.489362 (-1415 4205);
PAINT MONO (-1415 4205);
FORCEPROP 1 LAST VOLTAGE 4V
J 0
(-1375 4325);
DISPLAY 0.489362 (-1375 4325);
PAINT SKYBLUE (-1375 4325);
FORCEPROP 1 LAST VALUE 22UF
J 0
(-1375 4375);
DISPLAY 0.489362 (-1375 4375);
PAINT SKYBLUE (-1375 4375);
FORCEPROP 1 LAST TOLERANCE 20%
J 0
(-1375 4275);
DISPLAY 0.489362 (-1375 4275);
PAINT SKYBLUE (-1375 4275);
FORCEPROP 1 LAST MATERIAL X6S
J 0
(-1375 4225);
DISPLAY 0.489362 (-1375 4225);
PAINT SKYBLUE (-1375 4225);
FORCEPROP 1 LAST PACK_TYPE C0805
J 0
(-1375 4125);
DISPLAY 0.489362 (-1375 4125);
PAINT SKYBLUE (-1375 4125);
FORCEPROP 2 LAST CDS_LIB pure_quanta
J 0
(-1425 4325);
DISPLAY INVISIBLE (-1425 4325);
FORCEPROP 1 LAST PATH I28
J 0
(-1375 4475);
DISPLAY 0.978723 (-1375 4475);
PAINT WHITE (-1375 4475);
DISPLAY INVISIBLE (-1375 4475);
FORCEPROP 1 LAST PART_NUMBER CH622KMEA03
J 0
(-1375 4175);
DISPLAY 0.489362 (-1375 4175);
PAINT SKYBLUE (-1375 4175);
DISPLAY INVISIBLE (-1375 4175);
FORCEADD UNIVERSAL_GND..1
(-1000 3975);
FORCEPROP 3 LASTPIN (-1000 4025) SIG_NAME GND\g
J 0
(-990 4035);
DISPLAY 0.659574 (-990 4035);
PAINT MONO (-990 4035);
DISPLAY INVISIBLE (-990 4035);
FORCEPROP 2 LAST CDS_LIB pure_quanta_power
J 0
(-1000 3975);
DISPLAY INVISIBLE (-1000 3975);
FORCEPROP 1 LAST HDL_POWER GND
J 1
(-975 3900);
DISPLAY 0.872340 (-975 3900);
PAINT GREEN (-975 3900);
DISPLAY INVISIBLE (-975 3900);
FORCEPROP 1 LAST PATH I29
J 0
(-925 3975);
DISPLAY 0.872340 (-925 3975);
PAINT AQUA (-925 3975);
DISPLAY INVISIBLE (-925 3975);
FORCEADD UNIVERSAL_GND..1
(-7675 3950);
FORCEPROP 3 LASTPIN (-7675 4000) SIG_NAME GND\g
J 0
(-7665 4010);
DISPLAY 0.659574 (-7665 4010);
PAINT MONO (-7665 4010);
DISPLAY INVISIBLE (-7665 4010);
FORCEPROP 2 LAST CDS_LIB pure_quanta_power
J 0
(-7675 3950);
DISPLAY INVISIBLE (-7675 3950);
FORCEPROP 1 LAST HDL_POWER GND
J 1
(-7650 3875);
DISPLAY 0.872340 (-7650 3875);
PAINT GREEN (-7650 3875);
DISPLAY INVISIBLE (-7650 3875);
FORCEPROP 1 LAST PATH I3
J 0
(-7600 3950);
DISPLAY 0.872340 (-7600 3950);
PAINT AQUA (-7600 3950);
DISPLAY INVISIBLE (-7600 3950);
FORCEADD Q_CAP..1
(-1000 4325);
FORCEPROP 1 LAST LOCATION PC355_3
J 0
(-950 4425);
DISPLAY 0.489362 (-950 4425);
PAINT SKYBLUE (-950 4425);
FORCEPROP 0 LAST $SEC 1
J 0
(-950 4450);
DISPLAY 0.680851 (-950 4450);
PAINT MONO (-950 4450);
DISPLAY INVISIBLE (-950 4450);
FORCEPROP 0 LAST CDS_SEC 1
J 0
(-950 4450);
DISPLAY 1.021277 (-950 4450);
DISPLAY INVISIBLE (-950 4450);
FORCEPROP 1 LASTPIN (-1000 4425) $PN 1
J 0
(-990 4405);
DISPLAY 0.489362 (-990 4405);
PAINT MONO (-990 4405);
FORCEPROP 1 LASTPIN (-1000 4225) $PN 2
J 0
(-990 4205);
DISPLAY 0.489362 (-990 4205);
PAINT MONO (-990 4205);
FORCEPROP 1 LAST VOLTAGE 4V
J 0
(-950 4325);
DISPLAY 0.489362 (-950 4325);
PAINT SKYBLUE (-950 4325);
FORCEPROP 1 LAST VALUE 22UF
J 0
(-950 4375);
DISPLAY 0.489362 (-950 4375);
PAINT SKYBLUE (-950 4375);
FORCEPROP 1 LAST TOLERANCE 20%
J 0
(-950 4275);
DISPLAY 0.489362 (-950 4275);
PAINT SKYBLUE (-950 4275);
FORCEPROP 1 LAST MATERIAL X6S
J 0
(-950 4225);
DISPLAY 0.489362 (-950 4225);
PAINT SKYBLUE (-950 4225);
FORCEPROP 1 LAST PACK_TYPE C0805
J 0
(-950 4125);
DISPLAY 0.489362 (-950 4125);
PAINT SKYBLUE (-950 4125);
FORCEPROP 2 LAST CDS_LIB pure_quanta
J 0
(-1000 4325);
DISPLAY INVISIBLE (-1000 4325);
FORCEPROP 1 LAST PATH I30
J 0
(-950 4475);
DISPLAY 0.978723 (-950 4475);
PAINT WHITE (-950 4475);
DISPLAY INVISIBLE (-950 4475);
FORCEPROP 1 LAST PART_NUMBER CH622KMEA03
J 0
(-950 4175);
DISPLAY 0.489362 (-950 4175);
PAINT SKYBLUE (-950 4175);
DISPLAY INVISIBLE (-950 4175);
FORCEADD Q_CAP..1
(-4000 5375);
FORCEPROP 1 LAST LOCATION PC351_3
J 0
(-3950 5475);
DISPLAY 0.489362 (-3950 5475);
PAINT SKYBLUE (-3950 5475);
FORCEPROP 0 LAST $SEC 1
J 0
(-3950 5500);
DISPLAY 0.680851 (-3950 5500);
PAINT MONO (-3950 5500);
DISPLAY INVISIBLE (-3950 5500);
FORCEPROP 0 LAST CDS_SEC 1
J 0
(-3950 5500);
DISPLAY 1.021277 (-3950 5500);
DISPLAY INVISIBLE (-3950 5500);
FORCEPROP 1 LASTPIN (-4000 5475) $PN 1
J 0
(-3990 5455);
DISPLAY 0.489362 (-3990 5455);
PAINT MONO (-3990 5455);
FORCEPROP 1 LASTPIN (-4000 5275) $PN 2
J 0
(-3990 5255);
DISPLAY 0.489362 (-3990 5255);
PAINT MONO (-3990 5255);
FORCEPROP 1 LAST PACK_TYPE C0805
J 0
(-3950 5175);
DISPLAY 0.489362 (-3950 5175);
PAINT SKYBLUE (-3950 5175);
FORCEPROP 1 LAST VALUE 22UF
J 0
(-3950 5425);
DISPLAY 0.489362 (-3950 5425);
PAINT SKYBLUE (-3950 5425);
FORCEPROP 1 LAST MATERIAL X6S
J 0
(-3950 5275);
DISPLAY 0.489362 (-3950 5275);
PAINT SKYBLUE (-3950 5275);
FORCEPROP 1 LAST VOLTAGE 16V
J 0
(-3950 5375);
DISPLAY 0.489362 (-3950 5375);
PAINT SKYBLUE (-3950 5375);
FORCEPROP 1 LAST TOLERANCE 20%
J 0
(-3950 5325);
DISPLAY 0.489362 (-3950 5325);
PAINT SKYBLUE (-3950 5325);
FORCEPROP 2 LAST CDS_LIB pure_quanta
J 0
(-4000 5375);
DISPLAY INVISIBLE (-4000 5375);
FORCEPROP 1 LAST PATH I31
J 0
(-3950 5525);
DISPLAY 0.978723 (-3950 5525);
PAINT WHITE (-3950 5525);
DISPLAY INVISIBLE (-3950 5525);
FORCEPROP 1 LAST PART_NUMBER CH6223MEA01
J 0
(-3950 5225);
DISPLAY 0.489362 (-3950 5225);
PAINT SKYBLUE (-3950 5225);
DISPLAY INVISIBLE (-3950 5225);
FORCEADD Q_CAP..1
(-3700 5375);
FORCEPROP 1 LAST LOCATION PC352_3
J 0
(-3650 5475);
DISPLAY 0.489362 (-3650 5475);
PAINT SKYBLUE (-3650 5475);
FORCEPROP 0 LAST $SEC 1
J 0
(-3650 5500);
DISPLAY 0.680851 (-3650 5500);
PAINT MONO (-3650 5500);
DISPLAY INVISIBLE (-3650 5500);
FORCEPROP 0 LAST CDS_SEC 1
J 0
(-3650 5500);
DISPLAY 1.021277 (-3650 5500);
DISPLAY INVISIBLE (-3650 5500);
FORCEPROP 1 LASTPIN (-3700 5475) $PN 1
J 0
(-3690 5455);
DISPLAY 0.489362 (-3690 5455);
PAINT MONO (-3690 5455);
FORCEPROP 1 LASTPIN (-3700 5275) $PN 2
J 0
(-3690 5255);
DISPLAY 0.489362 (-3690 5255);
PAINT MONO (-3690 5255);
FORCEPROP 1 LAST PACK_TYPE C0805
J 0
(-3650 5175);
DISPLAY 0.489362 (-3650 5175);
PAINT SKYBLUE (-3650 5175);
FORCEPROP 1 LAST MATERIAL X6S
J 0
(-3650 5275);
DISPLAY 0.489362 (-3650 5275);
PAINT SKYBLUE (-3650 5275);
FORCEPROP 1 LAST VALUE 22UF
J 0
(-3650 5425);
DISPLAY 0.489362 (-3650 5425);
PAINT SKYBLUE (-3650 5425);
FORCEPROP 1 LAST VOLTAGE 16V
J 0
(-3650 5375);
DISPLAY 0.489362 (-3650 5375);
PAINT SKYBLUE (-3650 5375);
FORCEPROP 1 LAST TOLERANCE 20%
J 0
(-3650 5325);
DISPLAY 0.489362 (-3650 5325);
PAINT SKYBLUE (-3650 5325);
FORCEPROP 2 LAST CDS_LIB pure_quanta
J 0
(-3700 5375);
DISPLAY INVISIBLE (-3700 5375);
FORCEPROP 1 LAST PATH I32
J 0
(-3650 5525);
DISPLAY 0.978723 (-3650 5525);
PAINT WHITE (-3650 5525);
DISPLAY INVISIBLE (-3650 5525);
FORCEPROP 1 LAST PART_NUMBER CH6223MEA01
J 0
(-3650 5225);
DISPLAY 0.489362 (-3650 5225);
PAINT SKYBLUE (-3650 5225);
DISPLAY INVISIBLE (-3650 5225);
FORCEADD Q_CAP..1
(-3500 4725);
FORCEPROP 1 LAST LOCATION PC353
J 0
(-3450 4850);
DISPLAY 0.489362 (-3450 4850);
PAINT SKYBLUE (-3450 4850);
FORCEPROP 0 LAST $SEC 1
J 0
(-3450 4875);
DISPLAY 0.680851 (-3450 4875);
PAINT MONO (-3450 4875);
DISPLAY INVISIBLE (-3450 4875);
FORCEPROP 0 LAST CDS_SEC 1
J 0
(-3450 4875);
DISPLAY 1.021277 (-3450 4875);
DISPLAY INVISIBLE (-3450 4875);
FORCEPROP 1 LASTPIN (-3500 4825) $PN 1
J 0
(-3490 4805);
DISPLAY 0.489362 (-3490 4805);
PAINT MONO (-3490 4805);
FORCEPROP 1 LASTPIN (-3500 4625) $PN 2
J 0
(-3490 4605);
DISPLAY 0.489362 (-3490 4605);
PAINT MONO (-3490 4605);
FORCEPROP 1 LAST MATERIAL X7R
J 0
(-3450 4650);
DISPLAY 0.489362 (-3450 4650);
PAINT SKYBLUE (-3450 4650);
FORCEPROP 1 LAST TOLERANCE 10%
J 0
(-3450 4700);
DISPLAY 0.489362 (-3450 4700);
PAINT SKYBLUE (-3450 4700);
FORCEPROP 1 LAST VALUE 0.22UF
J 0
(-3450 4800);
DISPLAY 0.489362 (-3450 4800);
PAINT SKYBLUE (-3450 4800);
FORCEPROP 1 LAST VOLTAGE 16V
J 0
(-3450 4750);
DISPLAY 0.489362 (-3450 4750);
PAINT SKYBLUE (-3450 4750);
FORCEPROP 1 LAST PACK_TYPE 0402
J 0
(-3450 4550);
DISPLAY 0.489362 (-3450 4550);
PAINT SKYBLUE (-3450 4550);
FORCEPROP 2 LAST CDS_LIB pure_quanta
J 0
(-3500 4725);
DISPLAY INVISIBLE (-3500 4725);
FORCEPROP 1 LAST PATH I33
J 0
(-3450 4875);
DISPLAY 0.978723 (-3450 4875);
PAINT WHITE (-3450 4875);
DISPLAY INVISIBLE (-3450 4875);
FORCEPROP 1 LAST PART_NUMBER CH4223K1B00
J 0
(-3450 4600);
DISPLAY 0.489362 (-3450 4600);
PAINT SKYBLUE (-3450 4600);
DISPLAY INVISIBLE (-3450 4600);
FORCEADD Q_CAP..1
(-3325 5375);
FORCEPROP 1 LAST LOCATION PC353_3
J 0
(-3275 5475);
DISPLAY 0.489362 (-3275 5475);
PAINT SKYBLUE (-3275 5475);
FORCEPROP 0 LAST $SEC 1
J 0
(-3275 5500);
DISPLAY 0.680851 (-3275 5500);
PAINT MONO (-3275 5500);
DISPLAY INVISIBLE (-3275 5500);
FORCEPROP 0 LAST CDS_SEC 1
J 0
(-3275 5500);
DISPLAY 0.680851 (-3275 5500);
DISPLAY INVISIBLE (-3275 5500);
FORCEPROP 1 LASTPIN (-3325 5475) $PN 1
J 0
(-3315 5455);
DISPLAY 0.787234 (-3315 5455);
PAINT MONO (-3315 5455);
DISPLAY INVISIBLE (-3315 5455);
FORCEPROP 1 LASTPIN (-3325 5275) $PN 2
J 0
(-3315 5255);
DISPLAY 0.787234 (-3315 5255);
PAINT MONO (-3315 5255);
DISPLAY INVISIBLE (-3315 5255);
FORCEPROP 1 LAST MATERIAL X6S
J 0
(-3275 5275);
DISPLAY 0.489362 (-3275 5275);
PAINT SKYBLUE (-3275 5275);
FORCEPROP 1 LAST TOLERANCE 20%
J 0
(-3275 5325);
DISPLAY 0.489362 (-3275 5325);
PAINT SKYBLUE (-3275 5325);
FORCEPROP 1 LAST PACK_TYPE C0805
J 0
(-3275 5175);
DISPLAY 0.489362 (-3275 5175);
PAINT SKYBLUE (-3275 5175);
FORCEPROP 1 LAST VALUE 22UF
J 0
(-3275 5425);
DISPLAY 0.489362 (-3275 5425);
PAINT SKYBLUE (-3275 5425);
FORCEPROP 1 LAST VOLTAGE 16V
J 0
(-3275 5375);
DISPLAY 0.489362 (-3275 5375);
PAINT SKYBLUE (-3275 5375);
FORCEPROP 2 LAST CDS_LIB pure_quanta
J 0
(-3325 5375);
DISPLAY INVISIBLE (-3325 5375);
FORCEPROP 1 LAST PATH I34
J 0
(-3275 5525);
DISPLAY 0.978723 (-3275 5525);
PAINT WHITE (-3275 5525);
DISPLAY INVISIBLE (-3275 5525);
FORCEPROP 1 LAST PART_NUMBER CH6223MEA01
J 0
(-3275 5225);
DISPLAY 0.489362 (-3275 5225);
PAINT SKYBLUE (-3275 5225);
DISPLAY INVISIBLE (-3275 5225);
FORCEADD UNIVERSAL_GND..1
(-3325 5050);
FORCEPROP 3 LASTPIN (-3325 5100) SIG_NAME GND\g
J 0
(-3315 5110);
DISPLAY 0.659574 (-3315 5110);
PAINT MONO (-3315 5110);
DISPLAY INVISIBLE (-3315 5110);
FORCEPROP 2 LAST CDS_LIB pure_quanta_power
J 0
(-3325 5050);
DISPLAY INVISIBLE (-3325 5050);
FORCEPROP 1 LAST HDL_POWER GND
J 1
(-3300 4975);
DISPLAY 0.872340 (-3300 4975);
PAINT GREEN (-3300 4975);
DISPLAY INVISIBLE (-3300 4975);
FORCEPROP 1 LAST PATH I35
J 0
(-3250 5050);
DISPLAY 0.872340 (-3250 5050);
PAINT AQUA (-3250 5050);
DISPLAY INVISIBLE (-3250 5050);
FORCEADD VCC_CORE..1
(-3325 5650);
FORCEPROP 3 LASTPIN (-3325 5600) SIG_NAME SW_P12V_AUX_PVDDCR_SOC_P1_FLT\g
J 0
(-3315 5610);
DISPLAY 0.659574 (-3315 5610);
PAINT MONO (-3315 5610);
DISPLAY INVISIBLE (-3315 5610);
FORCEPROP 1 LAST HDL_POWER SW_P12V_AUX_PVDDCR_SOC_P1_FLT
J 1
(-3325 5700);
DISPLAY 0.489362 (-3325 5700);
PAINT GREEN (-3325 5700);
FORCEPROP 2 LAST CDS_LIB pure_quanta_power
J 0
(-3325 5650);
DISPLAY INVISIBLE (-3325 5650);
FORCEPROP 1 LAST PATH I36
J 0
(-3275 5675);
DISPLAY 0.872340 (-3275 5675);
PAINT AQUA (-3275 5675);
DISPLAY INVISIBLE (-3275 5675);
FORCEADD VCC_CORE..1
(-1000 4650);
FORCEPROP 3 LASTPIN (-1000 4600) SIG_NAME PVDDCR_SOC_P1\g
J 0
(-990 4610);
DISPLAY 0.659574 (-990 4610);
PAINT MONO (-990 4610);
DISPLAY INVISIBLE (-990 4610);
FORCEPROP 1 LAST HDL_POWER PVDDCR_SOC_P1
J 1
(-1000 4700);
DISPLAY 0.489362 (-1000 4700);
PAINT GREEN (-1000 4700);
FORCEPROP 2 LAST CDS_LIB pure_quanta_power
J 0
(-1000 4650);
DISPLAY INVISIBLE (-1000 4650);
FORCEPROP 1 LAST PATH I37
J 0
(-950 4675);
DISPLAY 0.872340 (-950 4675);
PAINT AQUA (-950 4675);
DISPLAY INVISIBLE (-950 4675);
FORCEADD ISL99390FRZTR5935..1
(-5850 4500);
FORCEPROP 1 LAST LOCATION PU32
J 0
(-6150 5375);
DISPLAY 0.489362 (-6150 5375);
PAINT SKYBLUE (-6150 5375);
FORCEPROP 2 LAST $SEC 1
J 0
(-6150 5525);
DISPLAY 0.680851 (-6150 5525);
PAINT MONO (-6150 5525);
DISPLAY INVISIBLE (-6150 5525);
FORCEPROP 2 LAST CDS_SEC 1
J 0
(-6150 5525);
DISPLAY 1.021277 (-6150 5525);
DISPLAY INVISIBLE (-6150 5525);
FORCEPROP 2 LASTPIN (-5450 4050) $PN 2
J 0
(-5440 4060);
DISPLAY 0.489362 (-5440 4060);
PAINT MONO (-5440 4060);
FORCEPROP 2 LASTPIN (-5450 4850) $PN 33
J 0
(-5440 4860);
DISPLAY 0.489362 (-5440 4860);
PAINT MONO (-5440 4860);
FORCEPROP 2 LASTPIN (-6300 4250) $PN 31
J 2
(-6310 4260);
DISPLAY 0.489362 (-6310 4260);
PAINT MONO (-6310 4260);
FORCEPROP 2 LASTPIN (-6300 4650) $PN 35
J 2
(-6310 4660);
DISPLAY 0.489362 (-6310 4660);
PAINT MONO (-6310 4660);
FORCEPROP 2 LASTPIN (-5450 4200) $PN 6
J 0
(-5440 4210);
DISPLAY 0.489362 (-5440 4210);
PAINT MONO (-5440 4210);
FORCEPROP 2 LASTPIN (-5450 4150) $PN 41
J 0
(-5440 4160);
DISPLAY 0.489362 (-5440 4160);
PAINT MONO (-5440 4160);
FORCEPROP 2 LASTPIN (-6300 4500) $PN 38
J 2
(-6310 4510);
DISPLAY 0.489362 (-6310 4510);
PAINT MONO (-6310 4510);
FORCEPROP 2 LASTPIN (-6300 4200) $PN 37
J 2
(-6310 4210);
DISPLAY 0.489362 (-6310 4210);
PAINT MONO (-6310 4210);
FORCEPROP 2 LASTPIN (-5450 4000) $PN 5
J 0
(-5440 4010);
DISPLAY 0.489362 (-5440 4010);
PAINT MONO (-5440 4010);
FORCEPROP 2 LASTPIN (-5450 3950) $PN 7_9-20_24
J 0
(-5440 3960);
DISPLAY 0.489362 (-5440 3960);
PAINT MONO (-5440 3960);
FORCEPROP 2 LASTPIN (-5450 3900) $PN 40
J 0
(-5440 3910);
DISPLAY 0.489362 (-5440 3910);
PAINT MONO (-5440 3910);
FORCEPROP 2 LASTPIN (-5450 4600) $PN 32
J 0
(-5440 4610);
DISPLAY 0.489362 (-5440 4610);
PAINT MONO (-5440 4610);
FORCEPROP 2 LASTPIN (-6300 5150) $PN 4
J 2
(-6310 5160);
DISPLAY 0.489362 (-6310 5160);
PAINT MONO (-6310 5160);
FORCEPROP 2 LASTPIN (-6300 3900) $PN 34
J 2
(-6310 3910);
DISPLAY 0.489362 (-6310 3910);
PAINT MONO (-6310 3910);
FORCEPROP 2 LASTPIN (-6300 4400) $PN 39
J 2
(-6310 4410);
DISPLAY 0.489362 (-6310 4410);
PAINT MONO (-6310 4410);
FORCEPROP 2 LASTPIN (-5450 4500) $PN 10_19
J 0
(-5440 4510);
DISPLAY 0.489362 (-5440 4510);
PAINT MONO (-5440 4510);
FORCEPROP 2 LASTPIN (-6300 4000) $PN 36
J 2
(-6310 4010);
DISPLAY 0.489362 (-6310 4010);
PAINT MONO (-6310 4010);
FORCEPROP 2 LASTPIN (-6300 4850) $PN 3
J 2
(-6310 4860);
DISPLAY 0.489362 (-6310 4860);
PAINT MONO (-6310 4860);
FORCEPROP 2 LASTPIN (-5450 5150) $PN 25_29
J 0
(-5440 5160);
DISPLAY 0.489362 (-5440 5160);
PAINT MONO (-5440 5160);
FORCEPROP 2 LASTPIN (-5450 5100) $PN 30
J 0
(-5440 5110);
DISPLAY 0.489362 (-5440 5110);
PAINT MONO (-5440 5110);
FORCEPROP 2 LASTPIN (-5450 4250) $PN 1
J 0
(-5440 4260);
DISPLAY 0.489362 (-5440 4260);
PAINT MONO (-5440 4260);
FORCEPROP 2 LAST PART_TYPE SMLF
J 0
(-6150 5475);
DISPLAY 1.021277 (-6150 5475);
FORCEPROP 2 LAST VALUE ISL99390FRZ-TR5935
J 0
(-6150 5425);
DISPLAY 0.489362 (-6150 5425);
PAINT SKYBLUE (-6150 5425);
FORCEPROP 1 LAST MATERIAL IC
J 0
(-6150 5225);
DISPLAY 0.489362 (-6150 5225);
PAINT SKYBLUE (-6150 5225);
FORCEPROP 2 LAST CDS_LIB pure_quanta
J 0
(-5850 4500);
DISPLAY INVISIBLE (-5850 4500);
FORCEPROP 1 LAST CDS_LMAN_SYM_OUTLINE -300,700,250,-650
J 0
(-5850 4500);
DISPLAY 0.468085 (-5850 4500);
PAINT GREEN (-5850 4500);
DISPLAY INVISIBLE (-5850 4500);
FORCEPROP 1 LAST NEEDS_NO_SIZE TRUE
J 0
(-5850 4500);
DISPLAY 0.723404 (-5850 4500);
PAINT GREEN (-5850 4500);
DISPLAY INVISIBLE (-5850 4500);
FORCEPROP 1 LAST PATH I38
J 0
(-5850 4500);
DISPLAY 0.723404 (-5850 4500);
PAINT GREEN (-5850 4500);
DISPLAY INVISIBLE (-5850 4500);
FORCEPROP 1 LAST PART_NUMBER AL099390004
J 0
(-6150 5300);
DISPLAY 0.489362 (-6150 5300);
PAINT SKYBLUE (-6150 5300);
DISPLAY INVISIBLE (-6150 5300);
FORCEADD UNIVERSAL_GND..1
(-7325 4025);
FORCEPROP 3 LASTPIN (-7325 4075) SIG_NAME GND\g
J 0
(-7315 4085);
DISPLAY 0.659574 (-7315 4085);
PAINT MONO (-7315 4085);
DISPLAY INVISIBLE (-7315 4085);
FORCEPROP 2 LAST CDS_LIB pure_quanta_power
J 0
(-7325 4025);
DISPLAY INVISIBLE (-7325 4025);
FORCEPROP 1 LAST HDL_POWER GND
J 1
(-7300 3950);
DISPLAY 0.872340 (-7300 3950);
PAINT GREEN (-7300 3950);
DISPLAY INVISIBLE (-7300 3950);
FORCEPROP 1 LAST PATH I4
J 0
(-7250 4025);
DISPLAY 0.872340 (-7250 4025);
PAINT AQUA (-7250 4025);
DISPLAY INVISIBLE (-7250 4025);
FORCEADD OFFPAGE..1
(-6950 3900);
FORCEPROP 2 LAST $XR0 210 
J 0
(-7202 3900);
DISPLAY 0.638298 (-7202 3900);
PAINT MONO (-7202 3900);
FORCEPROP 2 LAST CDS_LIB standard
J 2
(-6950 3900);
DISPLAY INVISIBLE (-6950 3900);
FORCEPROP 1 LAST OFFPAGE TRUE
J 0
(-6625 3775);
DISPLAY 0.872340 (-6625 3775);
PAINT GREEN (-6625 3775);
DISPLAY INVISIBLE (-6625 3775);
FORCEPROP 1 LAST COMMENT_BODY TRUE
J 0
(-6825 3800);
DISPLAY 0.872340 (-6825 3800);
PAINT GREEN (-6825 3800);
DISPLAY INVISIBLE (-6825 3800);
FORCEPROP 2 LAST PATH I5
J 0
(-7225 3950);
DISPLAY 0.680851 (-7225 3950);
DISPLAY INVISIBLE (-7225 3950);
FORCEADD OFFPAGE..2
R 2
(-6975 4000);
FORCEPROP 2 LAST $XR1 210 
J 0
(-7230 3964);
DISPLAY 0.638298 (-7230 3964);
PAINT MONO (-7230 3964);
FORCEPROP 2 LAST $XR0 215 
J 0
(-7230 4000);
DISPLAY 0.638298 (-7230 4000);
PAINT MONO (-7230 4000);
FORCEPROP 2 LAST CDS_LIB standard
J 0
(-6975 4000);
DISPLAY INVISIBLE (-6975 4000);
FORCEPROP 1 LAST OFFPAGE TRUE
J 2
(-7300 3875);
DISPLAY 0.872340 (-7300 3875);
PAINT GREEN (-7300 3875);
DISPLAY INVISIBLE (-7300 3875);
FORCEPROP 1 LAST COMMENT_BODY TRUE
J 2
(-6930 3905);
DISPLAY 0.872340 (-6930 3905);
PAINT GREEN (-6930 3905);
DISPLAY INVISIBLE (-6930 3905);
FORCEPROP 2 LAST PATH I6
J 0
(-7250 4050);
DISPLAY 0.680851 (-7250 4050);
DISPLAY INVISIBLE (-7250 4050);
FORCEADD Q_RES..1
(-7000 4200);
FORCEPROP 1 LAST LOCATION PR214
J 0
(-7050 4250);
DISPLAY 0.489362 (-7050 4250);
PAINT SKYBLUE (-7050 4250);
FORCEPROP 0 LAST $SEC 1
J 0
(-7000 4275);
DISPLAY 0.680851 (-7000 4275);
PAINT MONO (-7000 4275);
DISPLAY INVISIBLE (-7000 4275);
FORCEPROP 0 LAST CDS_SEC 1
J 0
(-7000 4275);
DISPLAY 1.021277 (-7000 4275);
DISPLAY INVISIBLE (-7000 4275);
FORCEPROP 1 LASTPIN (-7100 4200) $PN 1
J 0
(-7088 4212);
DISPLAY 0.489362 (-7088 4212);
PAINT MONO (-7088 4212);
FORCEPROP 1 LASTPIN (-6900 4200) $PN 2
J 0
(-6938 4212);
DISPLAY 0.489362 (-6938 4212);
PAINT MONO (-6938 4212);
FORCEPROP 1 LAST MATERIAL EMPTY
J 0
(-7300 4100);
DISPLAY 0.489362 (-7300 4100);
PAINT RED (-7300 4100);
FORCEPROP 1 LAST TOLERANCE 1%
J 0
(-6875 4225);
DISPLAY 0.489362 (-6875 4225);
PAINT SKYBLUE (-6875 4225);
FORCEPROP 1 LAST VALUE 8.87K
J 2
(-7125 4225);
DISPLAY 0.489362 (-7125 4225);
PAINT SKYBLUE (-7125 4225);
FORCEPROP 1 LAST PACK_TYPE 0402LF
J 0
(-6900 4150);
DISPLAY 0.489362 (-6900 4150);
PAINT SKYBLUE (-6900 4150);
FORCEPROP 1 LAST WATTAGE 1/16W
J 0
(-6900 4100);
DISPLAY 0.489362 (-6900 4100);
PAINT SKYBLUE (-6900 4100);
FORCEPROP 2 LAST CDS_LIB pure_quanta
J 0
(-7000 4200);
DISPLAY INVISIBLE (-7000 4200);
FORCEPROP 1 LAST PATH I7
J 0
(-7050 4350);
DISPLAY 0.978723 (-7050 4350);
PAINT WHITE (-7050 4350);
DISPLAY INVISIBLE (-7050 4350);
FORCEPROP 1 LAST PART_NUMBER CS28872FB01
J 0
(-7300 4150);
DISPLAY 0.489362 (-7300 4150);
PAINT SKYBLUE (-7300 4150);
DISPLAY INVISIBLE (-7300 4150);
FORCEADD UNIVERSAL_GND..1
(-5275 3775);
FORCEPROP 3 LASTPIN (-5275 3825) SIG_NAME GND\g
J 0
(-5265 3835);
DISPLAY 0.659574 (-5265 3835);
PAINT MONO (-5265 3835);
DISPLAY INVISIBLE (-5265 3835);
FORCEPROP 2 LAST CDS_LIB pure_quanta_power
J 0
(-5275 3775);
DISPLAY INVISIBLE (-5275 3775);
FORCEPROP 1 LAST HDL_POWER GND
J 1
(-5250 3700);
DISPLAY 0.872340 (-5250 3700);
PAINT GREEN (-5250 3700);
DISPLAY INVISIBLE (-5250 3700);
FORCEPROP 1 LAST PATH I8
J 0
(-5200 3775);
DISPLAY 0.872340 (-5200 3775);
PAINT AQUA (-5200 3775);
DISPLAY INVISIBLE (-5200 3775);
FORCEADD UNIVERSAL_GND..1
(-4450 3550);
FORCEPROP 3 LASTPIN (-4450 3600) SIG_NAME GND\g
J 0
(-4440 3610);
DISPLAY 0.659574 (-4440 3610);
PAINT MONO (-4440 3610);
DISPLAY INVISIBLE (-4440 3610);
FORCEPROP 2 LAST CDS_LIB pure_quanta_power
J 0
(-4450 3550);
DISPLAY INVISIBLE (-4450 3550);
FORCEPROP 1 LAST HDL_POWER GND
J 1
(-4425 3475);
DISPLAY 0.872340 (-4425 3475);
PAINT GREEN (-4425 3475);
DISPLAY INVISIBLE (-4425 3475);
FORCEPROP 1 LAST PATH I9
J 0
(-4375 3550);
DISPLAY 0.872340 (-4375 3550);
PAINT AQUA (-4375 3550);
DISPLAY INVISIBLE (-4375 3550);
FORCEADD DNS..1
(-4475 3775);
PAINT RED (-4475 3775);
FORCEPROP 2 LAST CDS_LIB mstr_misc
J 0
(-4475 3775);
DISPLAY INVISIBLE (-4475 3775);
FORCEPROP 1 LAST COMMENT_BODY TRUE
R 1
J 0
(-4400 3550);
DISPLAY 0.872340 (-4400 3550);
PAINT GREEN (-4400 3550);
DISPLAY INVISIBLE (-4400 3550);
FORCEADD DNS..1
(-7000 4175);
PAINT RED (-7000 4175);
FORCEPROP 2 LAST CDS_LIB mstr_misc
J 0
(-7000 4175);
DISPLAY INVISIBLE (-7000 4175);
FORCEPROP 1 LAST COMMENT_BODY TRUE
R 1
J 0
(-6925 3950);
DISPLAY 0.872340 (-6925 3950);
PAINT GREEN (-6925 3950);
DISPLAY INVISIBLE (-6925 3950);
FORCEADD QUANTA_TITLE_BLOCK_C..1
(0 0);
FORCEPROP 0 LAST CDS_CON_LAST_MODIFIED Thu Sep 14 16:12:21 2023
J 0
(-1885 15);
DISPLAY INVISIBLE (-1885 15);
FORCEPROP 1 LAST CUSTOM_TXT_CDS <CON_LAST_MODIFIED>
J 0
(-1885 15);
DISPLAY 0.978723 (-1885 15);
FORCEPROP 2 LAST CUSTOM_TXT_CDS <XR_PAGE_TITLE>
J 0
(-7890 5250);
DISPLAY 0.638298 (-7890 5250);
PAINT PINK (-7890 5250);
DISPLAY INVISIBLE (-7890 5250);
FORCEPROP 1 LAST CUSTOM_TXT_CDS <NAME_2>
J 0
(-3175 50);
FORCEPROP 1 LAST CUSTOM_TXT_CDS <NAME_1>
J 0
(-3175 175);
FORCEPROP 1 LAST CUSTOM_TXT_CDS <Q_NUMBER>
J 0
(-1403 103);
DISPLAY 1.212766 (-1403 103);
FORCEPROP 1 LAST CUSTOM_TXT_CDS <Q_PROJ>
J 0
(-2382 102);
DISPLAY 1.212766 (-2382 102);
FORCEPROP 1 LAST CUSTOM_TXT_CDS <Q_REV>
J 0
(-184 103);
DISPLAY 1.212766 (-184 103);
FORCEPROP 1 LAST CUSTOM_TXT_CDS <CON_PAGE_NUM> OF <CON_TOTAL_PAGES>
J 0
(-446 18);
DISPLAY 0.978723 (-446 18);
FORCEPROP 1 LAST Q_TITLE PVDDCR_SOC_P1 VR PHASE 3
J 0
(-9325 50);
DISPLAY 2.446809 (-9325 50);
PAINT GREEN (-9325 50);
FORCEPROP 1 LAST CDS_LMAN_SYM_OUTLINE -9475,6775,100,-125
J 0
(0 0);
DISPLAY 0.468085 (0 0);
PAINT GREEN (0 0);
DISPLAY INVISIBLE (0 0);
FORCEPROP 2 LAST CDS_LIB pure_quanta
J 0
(0 0);
DISPLAY INVISIBLE (0 0);
FORCEPROP 2 LAST PAGE_BORDER TRUE
J 0
(-7890 5250);
DISPLAY 0.638298 (-7890 5250);
PAINT PINK (-7890 5250);
DISPLAY INVISIBLE (-7890 5250);
FORCEPROP 2 LAST CDS_XR_PAGE_TITLE CR-216 : @T6G_MB_LIB.T6G(SCH_1):PAGE216
J 0
(-7890 5250);
DISPLAY 0.638298 (-7890 5250);
PAINT PINK (-7890 5250);
DISPLAY INVISIBLE (-7890 5250);
FORCEPROP 1 LAST Q_DEPT BU9
J 1
(-3763 49);
DISPLAY 1.957447 (-3763 49);
PAINT GREEN (-3763 49);
DISPLAY INVISIBLE (-3763 49);
FORCEPROP 1 LAST COMMENT_BODY TRUE
J 0
(12 -13);
DISPLAY 0.978723 (12 -13);
PAINT GREEN (12 -13);
DISPLAY INVISIBLE (12 -13);
FORCEADD DNS..1
(-4475 4300);
PAINT RED (-4475 4300);
FORCEPROP 2 LAST CDS_LIB mstr_misc
J 0
(-4475 4300);
DISPLAY INVISIBLE (-4475 4300);
FORCEPROP 1 LAST COMMENT_BODY TRUE
R 1
J 0
(-4400 4075);
DISPLAY 0.872340 (-4400 4075);
PAINT GREEN (-4400 4075);
DISPLAY INVISIBLE (-4400 4075);
WIRE 16 -1 (-7350 4750)(-7350 4700);
WIRE 16 -1 (-7000 5325)(-7000 5200);
WIRE 16 -1 (-7675 4125)(-7675 4000);
WIRE 16 -1 (-7100 4200)(-7325 4200);
WIRE 16 -1 (-7325 4200)(-7325 4075);
WIRE 16 -1 (-4450 3675)(-4450 3600);
WIRE 16 -1 (-3700 5275)(-3700 5150);
WIRE 16 -1 (-3325 5150)(-3700 5150);
WIRE 16 -1 (-3700 5150)(-4000 5150);
WIRE 16 -1 (-4000 5275)(-4000 5150);
WIRE 16 -1 (-4325 5150)(-4000 5150);
WIRE 16 -1 (-3325 5275)(-3325 5150);
WIRE 16 -1 (-3325 5150)(-3325 5100);
WIRE 16 -1 (-4325 5275)(-4325 5150);
WIRE 16 -1 (-4650 5150)(-4325 5150);
WIRE 16 -1 (-4650 5275)(-4650 5150);
WIRE 16 -1 (-5050 5150)(-4650 5150);
WIRE 16 -1 (-5050 5275)(-5050 5150);
WIRE 16 -1 (-5450 4850)(-4575 4850);
FORCEPROP 2 LAST SIG_NAME SW_PVDDCR_SOC_P1_BOOT3
J 0
(-5335 4860);
DISPLAY 0.489362 (-5335 4860);
FORCEPROP 2 LASTPROP $XRERR UNIQUE?
J 0
(-5575 4860);
DISPLAY 0.638298 (-5575 4860);
PAINT MONO (-5575 4860);
DISPLAY INVISIBLE (-5575 4860);
WIRE 16 -1 (-3500 4625)(-3500 4600);
WIRE 16 -1 (-3500 4600)(-5450 4600);
FORCEPROP 2 LAST SIG_NAME SW_PVDDCR_SOC_P1_PH3
J 0
(-5335 4610);
DISPLAY 0.489362 (-5335 4610);
FORCEPROP 2 LASTPROP $XRERR UNIQUE?
J 0
(-5575 4610);
DISPLAY 0.638298 (-5575 4610);
PAINT MONO (-5575 4610);
DISPLAY INVISIBLE (-5575 4610);
WIRE 16 -1 (-4450 4400)(-4450 4500);
WIRE 16 -1 (-4450 4500)(-3050 4500);
WIRE 16 -1 (-5450 4500)(-4450 4500);
FORCEPROP 2 LAST SIG_NAME SW_PVDDCR_SOC_P1_SW3
J 0
(-5335 4510);
DISPLAY 0.489362 (-5335 4510);
FORCEPROP 2 LASTPROP $XRERR UNIQUE?
J 0
(-5575 4510);
DISPLAY 0.638298 (-5575 4510);
PAINT MONO (-5575 4510);
DISPLAY INVISIBLE (-5575 4510);
WIRE 16 -1 (-4100 3300)(-4700 3300);
FORCEPROP 2 LAST SIG_NAME PVDDCR_SOC_P1_VOS3
J 0
(-5335 4275);
DISPLAY 0.489362 (-5335 4275);
FORCEPROP 2 LASTPROP $XRERR UNIQUE?
J 0
(-5575 4275);
DISPLAY 0.638298 (-5575 4275);
PAINT MONO (-5575 4275);
DISPLAY INVISIBLE (-5575 4275);
WIRE 16 -1 (-4700 4250)(-4700 3300);
WIRE 16 -1 (-5450 4250)(-4700 4250);
WIRE 16 -1 (-5450 4200)(-4925 4200);
FORCEPROP 2 LAST SIG_NAME NC_PVDDCR_SOC_P1_GL1_3
J 0
(-5335 4210);
DISPLAY 0.489362 (-5335 4210);
FORCEPROP 2 LASTPROP $XRERR UNIQUE?
J 0
(-4895 4200);
DISPLAY 0.638298 (-4895 4200);
PAINT MONO (-4895 4200);
DISPLAY INVISIBLE (-4895 4200);
WIRE 16 -1 (-7850 4400)(-7675 4400);
WIRE 16 -1 (-6300 4400)(-7675 4400);
FORCEPROP 2 LAST SIG_NAME PVDDCR_CPU0_P1_VCCS
J 2
(-6360 4410);
DISPLAY 0.489362 (-6360 4410);
WIRE 16 -1 (-7675 4325)(-7675 4400);
WIRE 16 -1 (-3500 4850)(-3500 4825);
WIRE 16 -1 (-4375 4850)(-3500 4850);
FORCEPROP 2 LAST SIG_NAME SW_PVDDCR_SOC_P1_BOOT3_RC
J 2
(-3535 4860);
DISPLAY 0.489362 (-3535 4860);
FORCEPROP 2 LASTPROP $XRERR UNIQUE?
J 0
(-3775 4860);
DISPLAY 0.638298 (-3775 4860);
PAINT MONO (-3775 4860);
DISPLAY INVISIBLE (-3775 4860);
WIRE 16 -1 (-5450 5150)(-5350 5150);
WIRE 16 -1 (-5350 5550)(-5350 5150);
WIRE 16 -1 (-5350 5150)(-5350 5100);
WIRE 16 -1 (-5350 5100)(-5450 5100);
WIRE 16 -1 (-5350 5550)(-5050 5550);
WIRE 16 -1 (-5050 5550)(-4650 5550);
WIRE 16 -1 (-5050 5475)(-5050 5550);
WIRE 16 -1 (-4650 5550)(-4325 5550);
WIRE 16 -1 (-4650 5475)(-4650 5550);
WIRE 16 -1 (-4325 5550)(-4000 5550);
WIRE 16 -1 (-4325 5475)(-4325 5550);
WIRE 16 -1 (-4000 5550)(-3700 5550);
WIRE 16 -1 (-4000 5550)(-4000 5475);
WIRE 16 -1 (-3325 5550)(-3700 5550);
WIRE 16 -1 (-3700 5550)(-3700 5475);
WIRE 16 -1 (-3325 5600)(-3325 5550);
WIRE 16 -1 (-3325 5550)(-3325 5475);
WIRE 16 -1 (-4450 4200)(-4450 3875);
FORCEPROP 2 LAST SIG_NAME SW_PVDDCR_SOC_P1_SW3_RC
J 0
(-4410 4010);
DISPLAY 0.489362 (-4410 4010);
FORCEPROP 2 LASTPROP $XRERR UNIQUE?
J 0
(-4650 4010);
DISPLAY 0.638298 (-4650 4010);
PAINT MONO (-4650 4010);
DISPLAY INVISIBLE (-4650 4010);
WIRE 16 -1 (-1500 4500)(-1425 4500);
WIRE 16 -1 (-2250 4500)(-1500 4500);
WIRE 16 -1 (-1500 4500)(-1500 3300);
WIRE 16 -1 (-1425 4500)(-1000 4500);
WIRE 16 -1 (-1425 4500)(-1425 4425);
WIRE 16 -1 (-1000 4600)(-1000 4500);
WIRE 16 -1 (-1000 4500)(-1000 4425);
WIRE 16 -1 (-1500 3300)(-3900 3300);
WIRE 16 -1 (-1425 4225)(-1425 4100);
WIRE 16 -1 (-1000 4100)(-1425 4100);
WIRE 16 -1 (-1000 4225)(-1000 4100);
WIRE 16 -1 (-1000 4025)(-1000 4100);
WIRE 16 -1 (-2250 4250)(-1900 4250);
FORCEPROP 2 LAST SIG_NAME IND_SOC_P1_CPL3
J 0
(-2210 4260);
DISPLAY 0.489362 (-2210 4260);
WIRE 16 -1 (-3550 4250)(-3050 4250);
FORCEPROP 2 LAST SIG_NAME IND_SOC_P1_CPL0
J 0
(-3485 4275);
DISPLAY 0.489362 (-3485 4275);
FORCEPROP 2 LASTPROP $XRERR UNIQUE?
J 0
(-3725 4275);
DISPLAY 0.638298 (-3725 4275);
PAINT MONO (-3725 4275);
DISPLAY INVISIBLE (-3725 4275);
WIRE 16 -1 (-3825 4250)(-3750 4250);
WIRE 16 -1 (-3825 4200)(-3825 4250);
WIRE 16 -1 (-7350 5500)(-7350 5625);
WIRE 16 -1 (-7000 5625)(-7350 5625);
WIRE 16 -1 (-7350 5750)(-7350 5625);
WIRE 16 -1 (-6675 5625)(-7000 5625);
WIRE 16 -1 (-7000 5525)(-7000 5625);
WIRE 16 -1 (-6675 5150)(-6675 5625);
WIRE 16 -1 (-6675 5150)(-6300 5150);
WIRE 16 -1 (-6300 4500)(-6950 4500);
FORCEPROP 2 LAST SIG_NAME PVDDCR_SOC_P1_IMON3
J 2
(-6360 4510);
DISPLAY 0.489362 (-6360 4510);
WIRE 16 -1 (-7350 5025)(-6900 5025);
WIRE 16 -1 (-7350 5300)(-7350 5025);
WIRE 16 -1 (-7350 5025)(-7350 4950);
WIRE 16 -1 (-6900 5025)(-6900 4850);
FORCEPROP 2 LAST SIG_NAME PVDDCR_SOC_P1_VCC3
J 2
(-6385 4860);
DISPLAY 0.489362 (-6385 4860);
FORCEPROP 2 LASTPROP $XRERR UNIQUE?
J 0
(-6625 4860);
DISPLAY 0.638298 (-6625 4860);
PAINT MONO (-6625 4860);
DISPLAY INVISIBLE (-6625 4860);
WIRE 16 -1 (-6900 4850)(-6300 4850);
WIRE 16 -1 (-6900 4850)(-6900 4650);
WIRE 16 -1 (-6900 4650)(-6300 4650);
WIRE 16 -1 (-5450 4150)(-4925 4150);
FORCEPROP 2 LAST SIG_NAME NC_PVDDCR_SOC_P1_GL2_3
J 0
(-5335 4160);
DISPLAY 0.489362 (-5335 4160);
FORCEPROP 2 LASTPROP $XRERR UNIQUE?
J 0
(-4895 4150);
DISPLAY 0.638298 (-4895 4150);
PAINT MONO (-4895 4150);
DISPLAY INVISIBLE (-4895 4150);
WIRE 16 -1 (-5450 3900)(-5275 3900);
WIRE 16 -1 (-5275 3900)(-5275 3950);
WIRE 16 -1 (-5275 3825)(-5275 3900);
WIRE 16 -1 (-5275 3950)(-5275 4000);
WIRE 16 -1 (-5450 3950)(-5275 3950);
WIRE 16 -1 (-5275 4050)(-5275 4000);
WIRE 16 -1 (-5450 4000)(-5275 4000);
WIRE 16 -1 (-5275 4050)(-5450 4050);
WIRE 16 -1 (-6300 4250)(-6750 4250);
FORCEPROP 2 LAST SIG_NAME NC_PVDDCR_SOC_P1_DNC3
J 2
(-6360 4260);
DISPLAY 0.489362 (-6360 4260);
FORCEPROP 2 LASTPROP $XRERR UNIQUE?
J 0
(-6990 4250);
DISPLAY 0.638298 (-6990 4250);
PAINT MONO (-6990 4250);
DISPLAY INVISIBLE (-6990 4250);
WIRE 16 -1 (-6300 3900)(-6900 3900);
FORCEPROP 2 LAST SIG_NAME PVDDCR_SOC_P1_PWM3
J 2
(-6360 3910);
DISPLAY 0.489362 (-6360 3910);
WIRE 16 -1 (-6900 4200)(-6300 4200);
FORCEPROP 2 LAST SIG_NAME PVDDCR_SOC_P1_LSET3
J 2
(-6360 4210);
DISPLAY 0.489362 (-6360 4210);
FORCEPROP 2 LASTPROP $XRERR UNIQUE?
J 0
(-6600 4210);
DISPLAY 0.638298 (-6600 4210);
PAINT MONO (-6600 4210);
DISPLAY INVISIBLE (-6600 4210);
WIRE 16 -1 (-6300 4000)(-6925 4000);
FORCEPROP 2 LAST SIG_NAME PVDDCR_SOC_P1_TEMP1
J 2
(-6360 4010);
DISPLAY 0.489362 (-6360 4010);
DOT 1 (-4000 5550);
DOT 1 (-7675 4400);
DOT 1 (-5275 3900);
DOT 1 (-5275 4000);
DOT 1 (-5275 3950);
DOT 1 (-7350 5025);
DOT 1 (-7350 5625);
DOT 1 (-6900 4850);
DOT 1 (-7000 5625);
DOT 1 (-5350 5150);
DOT 1 (-4650 5150);
DOT 1 (-4450 4500);
DOT 1 (-4325 5150);
DOT 1 (-5050 5550);
DOT 1 (-4650 5550);
DOT 1 (-4325 5550);
DOT 1 (-1000 4100);
DOT 1 (-4000 5150);
DOT 1 (-3700 5150);
DOT 1 (-3325 5150);
DOT 1 (-3700 5550);
DOT 1 (-3325 5550);
DOT 1 (-1500 4500);
DOT 1 (-1425 4500);
DOT 1 (-1000 4500);
FORCENOTE
PVDDCR_SOC_P1_PHASE3
(-6425 5900) 0;
DISPLAY LEFT (-6425 5900);
DISPLAY 1.595745 (-6425 5900);
PAINT WHITE (-6425 5900);
FORCENOTE
DCR=0.17M OHM
(-3725 4050) 0;
DISPLAY LEFT (-3725 4050);
DISPLAY 0.638298 (-3725 4050);
PAINT WHITE (-3725 4050);
FORCENOTE
HCME656510Q-221QL
(-3725 4200) 0;
DISPLAY LEFT (-3725 4200);
DISPLAY 0.638298 (-3725 4200);
PAINT WHITE (-3725 4200);
FORCENOTE
ISAT:30A@100C
(-3725 4150) 0;
DISPLAY LEFT (-3725 4150);
DISPLAY 0.638298 (-3725 4150);
PAINT WHITE (-3725 4150);
FORCENOTE
6.5*6.5*10.0
(-3725 4100) 0;
DISPLAY LEFT (-3725 4100);
DISPLAY 0.638298 (-3725 4100);
PAINT WHITE (-3725 4100);
FORCENOTE
2ND=CV+22Y0EZ01
(-3725 4000) 0;
DISPLAY LEFT (-3725 4000);
DISPLAY 0.638298 (-3725 4000);
PAINT WHITE (-3725 4000);
FORCENOTE
2ND=CV+15^0TZ01
(-2250 4575) 0;
DISPLAY LEFT (-2250 4575);
DISPLAY 0.638298 (-2250 4575);
PAINT WHITE (-2250 4575);
FORCENOTE
11.0*7.5*12.5
(-2250 4725) 0;
DISPLAY LEFT (-2250 4725);
DISPLAY 0.638298 (-2250 4725);
PAINT WHITE (-2250 4725);
FORCENOTE
DCR=2-3,0.27M OHM
(-2250 4625) 0;
DISPLAY LEFT (-2250 4625);
DISPLAY 0.638298 (-2250 4625);
PAINT WHITE (-2250 4625);
FORCENOTE
DCR=1-4,0.105M OHM
(-2250 4675) 0;
DISPLAY LEFT (-2250 4675);
DISPLAY 0.638298 (-2250 4675);
PAINT WHITE (-2250 4675);
FORCENOTE
ISAT:70A@100C
(-2250 4775) 0;
DISPLAY LEFT (-2250 4775);
DISPLAY 0.638298 (-2250 4775);
PAINT WHITE (-2250 4775);
FORCENOTE
PGL6303.151HLT
(-2250 4825) 0;
DISPLAY LEFT (-2250 4825);
DISPLAY 0.638298 (-2250 4825);
PAINT WHITE (-2250 4825);
QUIT
